(kicad_pcb
	(version 20221018)
	(generator pcbnew)
	(general
    (thickness 1.62)
  )
	(paper "A4")
	(title_block
    (title "ECP5 - Datacenter Secure Control Module (DC-SCM)")
    (date "2024-07-01")
    (rev "1.2.1")
		(comment 9 "footprints 280-287 of 506")
	)
	(layers
    (0 "F.Cu" signal)
    (1 "In1.Cu" power)
    (2 "In2.Cu" signal)
    (3 "In3.Cu" power)
    (4 "In4.Cu" power)
    (5 "In5.Cu" signal)
    (6 "In6.Cu" power)
    (31 "B.Cu" signal)
    (32 "B.Adhes" user "B.Adhesive")
    (33 "F.Adhes" user "F.Adhesive")
    (34 "B.Paste" user)
    (35 "F.Paste" user)
    (36 "B.SilkS" user "B.Silkscreen")
    (37 "F.SilkS" user "F.Silkscreen")
    (38 "B.Mask" user)
    (39 "F.Mask" user)
    (40 "Dwgs.User" user "User.Drawings")
    (41 "Cmts.User" user "User.Comments")
    (42 "Eco1.User" user "User.Eco1")
    (43 "Eco2.User" user "User.Eco2")
    (44 "Edge.Cuts" user)
    (45 "Margin" user)
    (46 "B.CrtYd" user "B.Courtyard")
    (47 "F.CrtYd" user "F.Courtyard")
    (48 "B.Fab" user)
    (49 "F.Fab" user)
  )
	(footprint "antmicro-footprints:C_0402_1005Metric" (layer "B.Cu")
    (at 110.7 132.2 90)
    (descr "Capacitor SMD 0402")
    (tags "capacitor SMD 0402")
    (property "Author" "Antmicro")
    (property "Dielectric" "")
    (property "License" "Apache-2.0")
    (property "MPN" "GRM155R61A475MEAAD")
    (property "Manufacturer" "Murata")
    (property "Public" "False")
    (property "Sheetfile" "fpga-power-supply.kicad_sch")
    (property "Sheetname" "FPGA power supply")
    (property "Val" "4u7")
    (property "Voltage" "")
    (property "ki_description" "SMD Multilayer Ceramic Capacitor, 4.7 µF, 10 V, 0402 [1005 Metric], ± 20%, X5R, GRM Series")
    (property "ki_keywords" "0402, SMT, CAPACITOR, PASSIVE")
    (attr smd)
    (fp_text reference "C158" (at -20.875 -0.13 90) (layer "B.SilkS")
        (effects (font (size 0.7 0.7) (thickness 0.127)) (justify mirror))
    )
    (fp_text value "C_4u7_0402" (at 0 -1.17 90) (layer "B.Fab")
        (effects (font (size 1 1) (thickness 0.15)) (justify mirror))
    )
    (fp_text user "Author: Antmicro" (at -0.939 -3.399 270) (layer "B.Fab") hide
        (effects (font (size 0.7 0.7) (thickness 0.15)) (justify left bottom mirror))
    )
    (fp_text user "${REFERENCE}" (at 0 0 90) (layer "B.Fab")
        (effects (font (size 0.25 0.25) (thickness 0.04)) (justify mirror))
    )
    (fp_text user "License: Apache-2.0" (at -0.939 -5.799 270) (layer "B.Fab") hide
        (effects (font (size 0.7 0.7) (thickness 0.15)) (justify left bottom mirror))
    )
    (fp_rect (start -0.925 0.47) (end 0.925 -0.47)
      (stroke (width 0.05) (type default)) (fill none) (layer "B.CrtYd"))
    (fp_line (start -0.494 -0.248) (end -0.494 0.25)
      (stroke (width 0.15) (type solid)) (layer "B.Fab"))
    (fp_line (start -0.494 0.25) (end 0.504 0.25)
      (stroke (width 0.15) (type solid)) (layer "B.Fab"))
    (fp_line (start 0.504 -0.248) (end -0.494 -0.248)
      (stroke (width 0.15) (type solid)) (layer "B.Fab"))
    (fp_line (start 0.504 0.25) (end 0.504 -0.248)
      (stroke (width 0.15) (type solid)) (layer "B.Fab"))
    (pad "1" smd roundrect (at -0.48 0 90) (size 0.59 0.64) (layers "B.Cu" "B.Paste" "B.Mask") (roundrect_rratio 0.25)
      (net 1 "GND") (pintype "passive"))
    (pad "2" smd roundrect (at 0.48 0 90) (size 0.59 0.64) (layers "B.Cu" "B.Paste" "B.Mask") (roundrect_rratio 0.25)
      (net 304 "/FPGA power supply/VCCAUX") (pintype "passive"))
  )
	(footprint "antmicro-footprints:C_0402_1005Metric" (layer "B.Cu")
    (at 112.75 126.3 90)
    (descr "Capacitor SMD 0402")
    (tags "capacitor SMD 0402")
    (property "Author" "Antmicro")
    (property "Dielectric" "")
    (property "License" "Apache-2.0")
    (property "MPN" "GRM155R61A475MEAAD")
    (property "Manufacturer" "Murata")
    (property "Public" "False")
    (property "Sheetfile" "fpga-power-supply.kicad_sch")
    (property "Sheetname" "FPGA power supply")
    (property "Val" "4u7")
    (property "Voltage" "")
    (property "ki_description" "SMD Multilayer Ceramic Capacitor, 4.7 µF, 10 V, 0402 [1005 Metric], ± 20%, X5R, GRM Series")
    (property "ki_keywords" "0402, SMT, CAPACITOR, PASSIVE")
    (attr smd)
    (fp_text reference "C159" (at -0.25 3.8 90) (layer "B.SilkS")
        (effects (font (size 0.7 0.7) (thickness 0.127)) (justify mirror))
    )
    (fp_text value "C_4u7_0402" (at 0 -1.17 90) (layer "B.Fab")
        (effects (font (size 1 1) (thickness 0.15)) (justify mirror))
    )
    (fp_text user "Author: Antmicro" (at -0.939 -3.399 270) (layer "B.Fab") hide
        (effects (font (size 0.7 0.7) (thickness 0.15)) (justify left bottom mirror))
    )
    (fp_text user "${REFERENCE}" (at 0 0 90) (layer "B.Fab")
        (effects (font (size 0.25 0.25) (thickness 0.04)) (justify mirror))
    )
    (fp_text user "License: Apache-2.0" (at -0.939 -5.799 270) (layer "B.Fab") hide
        (effects (font (size 0.7 0.7) (thickness 0.15)) (justify left bottom mirror))
    )
    (fp_rect (start -0.925 0.47) (end 0.925 -0.47)
      (stroke (width 0.05) (type default)) (fill none) (layer "B.CrtYd"))
    (fp_line (start -0.494 -0.248) (end -0.494 0.25)
      (stroke (width 0.15) (type solid)) (layer "B.Fab"))
    (fp_line (start -0.494 0.25) (end 0.504 0.25)
      (stroke (width 0.15) (type solid)) (layer "B.Fab"))
    (fp_line (start 0.504 -0.248) (end -0.494 -0.248)
      (stroke (width 0.15) (type solid)) (layer "B.Fab"))
    (fp_line (start 0.504 0.25) (end 0.504 -0.248)
      (stroke (width 0.15) (type solid)) (layer "B.Fab"))
    (pad "1" smd roundrect (at -0.48 0 90) (size 0.59 0.64) (layers "B.Cu" "B.Paste" "B.Mask") (roundrect_rratio 0.25)
      (net 211 "VCC1V2") (pintype "passive"))
    (pad "2" smd roundrect (at 0.48 0 90) (size 0.59 0.64) (layers "B.Cu" "B.Paste" "B.Mask") (roundrect_rratio 0.25)
      (net 1 "GND") (pintype "passive"))
  )
	(footprint "antmicro-footprints:C_0402_1005Metric" (layer "B.Cu")
    (at 107.05 132.25 90)
    (descr "Capacitor SMD 0402")
    (tags "capacitor SMD 0402")
    (property "Author" "Antmicro")
    (property "Dielectric" "")
    (property "License" "Apache-2.0")
    (property "MPN" "C1005X5R1E474M050BB")
    (property "Manufacturer" "TDK")
    (property "Public" "False")
    (property "Sheetfile" "fpga-power-supply.kicad_sch")
    (property "Sheetname" "FPGA power supply")
    (property "Val" "470n")
    (property "Voltage" "")
    (property "ki_description" "SMD Multilayer Ceramic Capacitor, 0.47 µF, 25 V, 0402 [1005 Metric], ± 20%, X5R, C")
    (property "ki_keywords" "0402, SMT, CAPACITOR, PASSIVE, CERAMIC, MLCC")
    (attr smd)
    (fp_text reference "C163" (at -20.845 0.87 90) (layer "B.SilkS")
        (effects (font (size 0.7 0.7) (thickness 0.127)) (justify mirror))
    )
    (fp_text value "C_470n_0402" (at 0 -1.17 90) (layer "B.Fab")
        (effects (font (size 1 1) (thickness 0.15)) (justify mirror))
    )
    (fp_text user "${REFERENCE}" (at 0 0 90) (layer "B.Fab")
        (effects (font (size 0.25 0.25) (thickness 0.04)) (justify mirror))
    )
    (fp_text user "Author: Antmicro" (at -0.939 -3.399 270) (layer "B.Fab") hide
        (effects (font (size 0.7 0.7) (thickness 0.15)) (justify left bottom mirror))
    )
    (fp_text user "License: Apache-2.0" (at -0.939 -5.799 270) (layer "B.Fab") hide
        (effects (font (size 0.7 0.7) (thickness 0.15)) (justify left bottom mirror))
    )
    (fp_rect (start -0.925 0.47) (end 0.925 -0.47)
      (stroke (width 0.05) (type default)) (fill none) (layer "B.CrtYd"))
    (fp_line (start -0.494 -0.248) (end -0.494 0.25)
      (stroke (width 0.15) (type solid)) (layer "B.Fab"))
    (fp_line (start -0.494 0.25) (end 0.504 0.25)
      (stroke (width 0.15) (type solid)) (layer "B.Fab"))
    (fp_line (start 0.504 -0.248) (end -0.494 -0.248)
      (stroke (width 0.15) (type solid)) (layer "B.Fab"))
    (fp_line (start 0.504 0.25) (end 0.504 -0.248)
      (stroke (width 0.15) (type solid)) (layer "B.Fab"))
    (pad "1" smd roundrect (at -0.48 0 90) (size 0.59 0.64) (layers "B.Cu" "B.Paste" "B.Mask") (roundrect_rratio 0.25)
      (net 1 "GND") (pintype "passive"))
    (pad "2" smd roundrect (at 0.48 0 90) (size 0.59 0.64) (layers "B.Cu" "B.Paste" "B.Mask") (roundrect_rratio 0.25)
      (net 303 "/FPGA power supply/VCCA1") (pintype "passive"))
  )
	(footprint "antmicro-footprints:C_0402_1005Metric" (layer "B.Cu")
    (at 97.6 117.135714)
    (descr "Capacitor SMD 0402")
    (tags "capacitor SMD 0402")
    (property "Author" "Antmicro")
    (property "Dielectric" "")
    (property "License" "Apache-2.0")
    (property "MPN" "C1005X5R1E474M050BB")
    (property "Manufacturer" "TDK")
    (property "Public" "False")
    (property "Sheetfile" "fpga-power-supply.kicad_sch")
    (property "Sheetname" "FPGA power supply")
    (property "Val" "470n")
    (property "Voltage" "")
    (property "ki_description" "SMD Multilayer Ceramic Capacitor, 0.47 µF, 25 V, 0402 [1005 Metric], ± 20%, X5R, C")
    (property "ki_keywords" "0402, SMT, CAPACITOR, PASSIVE, CERAMIC, MLCC")
    (attr smd)
    (fp_text reference "C161" (at -2.58 -0.190714) (layer "B.SilkS")
        (effects (font (size 0.7 0.7) (thickness 0.127)) (justify mirror))
    )
    (fp_text value "C_470n_0402" (at 0 -1.17) (layer "B.Fab")
        (effects (font (size 1 1) (thickness 0.15)) (justify mirror))
    )
    (fp_text user "Author: Antmicro" (at -0.939 -3.399 180) (layer "B.Fab") hide
        (effects (font (size 0.7 0.7) (thickness 0.15)) (justify left bottom mirror))
    )
    (fp_text user "${REFERENCE}" (at 0 0) (layer "B.Fab")
        (effects (font (size 0.25 0.25) (thickness 0.04)) (justify mirror))
    )
    (fp_text user "License: Apache-2.0" (at -0.939 -5.799 180) (layer "B.Fab") hide
        (effects (font (size 0.7 0.7) (thickness 0.15)) (justify left bottom mirror))
    )
    (fp_rect (start -0.925 0.47) (end 0.925 -0.47)
      (stroke (width 0.05) (type default)) (fill none) (layer "B.CrtYd"))
    (fp_line (start -0.494 -0.248) (end -0.494 0.25)
      (stroke (width 0.15) (type solid)) (layer "B.Fab"))
    (fp_line (start -0.494 0.25) (end 0.504 0.25)
      (stroke (width 0.15) (type solid)) (layer "B.Fab"))
    (fp_line (start 0.504 -0.248) (end -0.494 -0.248)
      (stroke (width 0.15) (type solid)) (layer "B.Fab"))
    (fp_line (start 0.504 0.25) (end 0.504 -0.248)
      (stroke (width 0.15) (type solid)) (layer "B.Fab"))
    (pad "1" smd roundrect (at -0.48 0) (size 0.59 0.64) (layers "B.Cu" "B.Paste" "B.Mask") (roundrect_rratio 0.25)
      (net 1 "GND") (pintype "passive"))
    (pad "2" smd roundrect (at 0.48 0) (size 0.59 0.64) (layers "B.Cu" "B.Paste" "B.Mask") (roundrect_rratio 0.25)
      (net 304 "/FPGA power supply/VCCAUX") (pintype "passive"))
  )
	(footprint "antmicro-footprints:C_0402_1005Metric" (layer "B.Cu")
    (at 107.2 122 180)
    (descr "Capacitor SMD 0402")
    (tags "capacitor SMD 0402")
    (property "Author" "Antmicro")
    (property "Dielectric" "")
    (property "License" "Apache-2.0")
    (property "MPN" "C1005X5R1E474M050BB")
    (property "Manufacturer" "TDK")
    (property "Public" "False")
    (property "Sheetfile" "fpga-power-supply.kicad_sch")
    (property "Sheetname" "FPGA power supply")
    (property "Val" "470n")
    (property "Voltage" "")
    (property "ki_description" "SMD Multilayer Ceramic Capacitor, 0.47 µF, 25 V, 0402 [1005 Metric], ± 20%, X5R, C")
    (property "ki_keywords" "0402, SMT, CAPACITOR, PASSIVE, CERAMIC, MLCC")
    (attr smd)
    (fp_text reference "C162" (at 0.71 -22.315) (layer "B.SilkS")
        (effects (font (size 0.7 0.7) (thickness 0.127)) (justify mirror))
    )
    (fp_text value "C_470n_0402" (at 0 -1.17) (layer "B.Fab")
        (effects (font (size 1 1) (thickness 0.15)) (justify mirror))
    )
    (fp_text user "${REFERENCE}" (at 0 0) (layer "B.Fab")
        (effects (font (size 0.25 0.25) (thickness 0.04)) (justify mirror))
    )
    (fp_text user "Author: Antmicro" (at -0.939 -3.399) (layer "B.Fab") hide
        (effects (font (size 0.7 0.7) (thickness 0.15)) (justify left bottom mirror))
    )
    (fp_text user "License: Apache-2.0" (at -0.939 -5.799) (layer "B.Fab") hide
        (effects (font (size 0.7 0.7) (thickness 0.15)) (justify left bottom mirror))
    )
    (fp_rect (start -0.925 0.47) (end 0.925 -0.47)
      (stroke (width 0.05) (type default)) (fill none) (layer "B.CrtYd"))
    (fp_line (start -0.494 -0.248) (end -0.494 0.25)
      (stroke (width 0.15) (type solid)) (layer "B.Fab"))
    (fp_line (start -0.494 0.25) (end 0.504 0.25)
      (stroke (width 0.15) (type solid)) (layer "B.Fab"))
    (fp_line (start 0.504 -0.248) (end -0.494 -0.248)
      (stroke (width 0.15) (type solid)) (layer "B.Fab"))
    (fp_line (start 0.504 0.25) (end 0.504 -0.248)
      (stroke (width 0.15) (type solid)) (layer "B.Fab"))
    (pad "1" smd roundrect (at -0.48 0 180) (size 0.59 0.64) (layers "B.Cu" "B.Paste" "B.Mask") (roundrect_rratio 0.25)
      (net 211 "VCC1V2") (pintype "passive"))
    (pad "2" smd roundrect (at 0.48 0 180) (size 0.59 0.64) (layers "B.Cu" "B.Paste" "B.Mask") (roundrect_rratio 0.25)
      (net 1 "GND") (pintype "passive"))
  )
	(footprint "antmicro-footprints:C_0402_1005Metric" (layer "B.Cu")
    (at 100.75 113.8 -90)
    (descr "Capacitor SMD 0402")
    (tags "capacitor SMD 0402")
    (property "Author" "Antmicro")
    (property "Dielectric" "")
    (property "License" "Apache-2.0")
    (property "MPN" "C1005X5R1E474M050BB")
    (property "Manufacturer" "TDK")
    (property "Public" "False")
    (property "Sheetfile" "fpga-power-supply.kicad_sch")
    (property "Sheetname" "FPGA power supply")
    (property "Val" "470n")
    (property "Voltage" "")
    (property "ki_description" "SMD Multilayer Ceramic Capacitor, 0.47 µF, 25 V, 0402 [1005 Metric], ± 20%, X5R, C")
    (property "ki_keywords" "0402, SMT, CAPACITOR, PASSIVE, CERAMIC, MLCC")
    (attr smd)
    (fp_text reference "C164" (at -2.795 -0.01 90) (layer "B.SilkS")
        (effects (font (size 0.7 0.7) (thickness 0.127)) (justify mirror))
    )
    (fp_text value "C_470n_0402" (at 0 -1.17 90) (layer "B.Fab")
        (effects (font (size 1 1) (thickness 0.15)) (justify mirror))
    )
    (fp_text user "${REFERENCE}" (at 0 0 90) (layer "B.Fab")
        (effects (font (size 0.25 0.25) (thickness 0.04)) (justify mirror))
    )
    (fp_text user "Author: Antmicro" (at -0.939 -3.399 90) (layer "B.Fab") hide
        (effects (font (size 0.7 0.7) (thickness 0.15)) (justify left bottom mirror))
    )
    (fp_text user "License: Apache-2.0" (at -0.939 -5.799 90) (layer "B.Fab") hide
        (effects (font (size 0.7 0.7) (thickness 0.15)) (justify left bottom mirror))
    )
    (fp_rect (start -0.925 0.47) (end 0.925 -0.47)
      (stroke (width 0.05) (type default)) (fill none) (layer "B.CrtYd"))
    (fp_line (start -0.494 -0.248) (end -0.494 0.25)
      (stroke (width 0.15) (type solid)) (layer "B.Fab"))
    (fp_line (start -0.494 0.25) (end 0.504 0.25)
      (stroke (width 0.15) (type solid)) (layer "B.Fab"))
    (fp_line (start 0.504 -0.248) (end -0.494 -0.248)
      (stroke (width 0.15) (type solid)) (layer "B.Fab"))
    (fp_line (start 0.504 0.25) (end 0.504 -0.248)
      (stroke (width 0.15) (type solid)) (layer "B.Fab"))
    (pad "1" smd roundrect (at -0.48 0 270) (size 0.59 0.64) (layers "B.Cu" "B.Paste" "B.Mask") (roundrect_rratio 0.25)
      (net 1 "GND") (pintype "passive"))
    (pad "2" smd roundrect (at 0.48 0 270) (size 0.59 0.64) (layers "B.Cu" "B.Paste" "B.Mask") (roundrect_rratio 0.25)
      (net 304 "/FPGA power supply/VCCAUX") (pintype "passive"))
  )
	(footprint "antmicro-footprints:C_0402_1005Metric" (layer "B.Cu")
    (at 107.15 120.45 180)
    (descr "Capacitor SMD 0402")
    (tags "capacitor SMD 0402")
    (property "Author" "Antmicro")
    (property "Dielectric" "")
    (property "License" "Apache-2.0")
    (property "MPN" "C1005X5R1E474M050BB")
    (property "Manufacturer" "TDK")
    (property "Public" "False")
    (property "Sheetfile" "fpga-power-supply.kicad_sch")
    (property "Sheetname" "FPGA power supply")
    (property "Val" "470n")
    (property "Voltage" "")
    (property "ki_description" "SMD Multilayer Ceramic Capacitor, 0.47 µF, 25 V, 0402 [1005 Metric], ± 20%, X5R, C")
    (property "ki_keywords" "0402, SMT, CAPACITOR, PASSIVE, CERAMIC, MLCC")
    (attr smd)
    (fp_text reference "C165" (at 0.6 -22.9) (layer "B.SilkS")
        (effects (font (size 0.7 0.7) (thickness 0.127)) (justify mirror))
    )
    (fp_text value "C_470n_0402" (at 0 -1.17) (layer "B.Fab")
        (effects (font (size 1 1) (thickness 0.15)) (justify mirror))
    )
    (fp_text user "Author: Antmicro" (at -0.939 -3.399) (layer "B.Fab") hide
        (effects (font (size 0.7 0.7) (thickness 0.15)) (justify left bottom mirror))
    )
    (fp_text user "License: Apache-2.0" (at -0.939 -5.799) (layer "B.Fab") hide
        (effects (font (size 0.7 0.7) (thickness 0.15)) (justify left bottom mirror))
    )
    (fp_text user "${REFERENCE}" (at 0 0) (layer "B.Fab")
        (effects (font (size 0.25 0.25) (thickness 0.04)) (justify mirror))
    )
    (fp_rect (start -0.925 0.47) (end 0.925 -0.47)
      (stroke (width 0.05) (type default)) (fill none) (layer "B.CrtYd"))
    (fp_line (start -0.494 -0.248) (end -0.494 0.25)
      (stroke (width 0.15) (type solid)) (layer "B.Fab"))
    (fp_line (start -0.494 0.25) (end 0.504 0.25)
      (stroke (width 0.15) (type solid)) (layer "B.Fab"))
    (fp_line (start 0.504 -0.248) (end -0.494 -0.248)
      (stroke (width 0.15) (type solid)) (layer "B.Fab"))
    (fp_line (start 0.504 0.25) (end 0.504 -0.248)
      (stroke (width 0.15) (type solid)) (layer "B.Fab"))
    (pad "1" smd roundrect (at -0.48 0 180) (size 0.59 0.64) (layers "B.Cu" "B.Paste" "B.Mask") (roundrect_rratio 0.25)
      (net 211 "VCC1V2") (pintype "passive"))
    (pad "2" smd roundrect (at 0.48 0 180) (size 0.59 0.64) (layers "B.Cu" "B.Paste" "B.Mask") (roundrect_rratio 0.25)
      (net 1 "GND") (pintype "passive"))
  )
	(footprint "antmicro-footprints:C_0402_1005Metric" (layer "B.Cu")
    (at 112.45 130 90)
    (descr "Capacitor SMD 0402")
    (tags "capacitor SMD 0402")
    (property "Author" "Antmicro")
    (property "Dielectric" "")
    (property "License" "Apache-2.0")
    (property "MPN" "C1005X5R1E474M050BB")
    (property "Manufacturer" "TDK")
    (property "Public" "False")
    (property "Sheetfile" "fpga-power-supply.kicad_sch")
    (property "Sheetname" "FPGA power supply")
    (property "Val" "470n")
    (property "Voltage" "")
    (property "ki_description" "SMD Multilayer Ceramic Capacitor, 0.47 µF, 25 V, 0402 [1005 Metric], ± 20%, X5R, C")
    (property "ki_keywords" "0402, SMT, CAPACITOR, PASSIVE, CERAMIC, MLCC")
    (attr smd)
    (fp_text reference "C166" (at -0.055 1.18 90) (layer "B.SilkS")
        (effects (font (size 0.7 0.7) (thickness 0.127)) (justify mirror))
    )
    (fp_text value "C_470n_0402" (at 0 -1.17 90) (layer "B.Fab")
        (effects (font (size 1 1) (thickness 0.15)) (justify mirror))
    )
    (fp_text user "License: Apache-2.0" (at -0.939 -5.799 270) (layer "B.Fab") hide
        (effects (font (size 0.7 0.7) (thickness 0.15)) (justify left bottom mirror))
    )
    (fp_text user "${REFERENCE}" (at 0 0 90) (layer "B.Fab")
        (effects (font (size 0.25 0.25) (thickness 0.04)) (justify mirror))
    )
    (fp_text user "Author: Antmicro" (at -0.939 -3.399 270) (layer "B.Fab") hide
        (effects (font (size 0.7 0.7) (thickness 0.15)) (justify left bottom mirror))
    )
    (fp_rect (start -0.925 0.47) (end 0.925 -0.47)
      (stroke (width 0.05) (type default)) (fill none) (layer "B.CrtYd"))
    (fp_line (start -0.494 -0.248) (end -0.494 0.25)
      (stroke (width 0.15) (type solid)) (layer "B.Fab"))
    (fp_line (start -0.494 0.25) (end 0.504 0.25)
      (stroke (width 0.15) (type solid)) (layer "B.Fab"))
    (fp_line (start 0.504 -0.248) (end -0.494 -0.248)
      (stroke (width 0.15) (type solid)) (layer "B.Fab"))
    (fp_line (start 0.504 0.25) (end 0.504 -0.248)
      (stroke (width 0.15) (type solid)) (layer "B.Fab"))
    (pad "1" smd roundrect (at -0.48 0 90) (size 0.59 0.64) (layers "B.Cu" "B.Paste" "B.Mask") (roundrect_rratio 0.25)
      (net 1 "GND") (pintype "passive"))
    (pad "2" smd roundrect (at 0.48 0 90) (size 0.59 0.64) (layers "B.Cu" "B.Paste" "B.Mask") (roundrect_rratio 0.25)
      (net 303 "/FPGA power supply/VCCA1") (pintype "passive"))
  )
)
